FILE_TYPE = CONNECTIVITY;
{Allegro Design Entry HDL 17.4-2019 S026 (4007227) 1/17/2022}
"PAGE_NUMBER" = 60;
0"NC";
1"GND\g";
2"GND\g";
%"UNIVERSAL_GND"
"1","(-1075,4675)","1","pure_quanta_power","I1";
;
CDS_LIB"pure_quanta_power"
HDL_POWER"GND";
"A"2;
%"UNIVERSAL_GND"
"1","(-1650,3225)","1","pure_quanta_power","I2";
;
CDS_LIB"pure_quanta_power"
HDL_POWER"GND";
"A"1;
%"GENOA_SP5"
"40","(-4525,3950)","1","pure_quanta","I3";
;
LOCATION"U26"
$SEC"40"
CDS_SEC"40"
PART_TYPE"SMLF"
MATERIAL"IO"
VALUE"SOCKET6096_13568-001"
CDS_LIB"pure_quanta"
CDS_LMAN_SYM_OUTLINE"-400,3350,400,-3350"
NEEDS_NO_SIZE"TRUE"
PART_NUMBER"DGA^6000030";
"VSS_V68"
$PN"V68"2;
"VSS_BV42"
$PN"BV42"2;
"VSS_CT52"
$PN"CT52"2;
"VSS_CM50"
$PN"CM50"2;
"VSS_K59"
$PN"K59"2;
"VSS_DA56"
$PN"DA56"2;
"VSS_CG42"
$PN"CG42"2;
"VSS_AE4"
$PN"AE4"2;
"VSS_AH33"
$PN"AH33"2;
"VSS_BW25"
$PN"BW25"2;
"VSS_CU58"
$PN"CU58"2;
"VSS_P25"
$PN"P25"2;
"VSS_P68"
$PN"P68"2;
"VSS_AN20"
$PN"AN20"2;
"VSS_CC22"
$PN"CC22"2;
"VSS_CF46"
$PN"CF46"2;
"VSS_V27"
$PN"V27"2;
"VSS_AA42"
$PN"AA42"2;
"VSS_AD31"
$PN"AD31"2;
"VSS_AJ13"
$PN"AJ13"2;
"VSS_AA72"
$PN"AA72"2;
"VSS_CK10"
$PN"CK10"2;
"VSS_CN54"
$PN"CN54"2;
"VSS_K23"
$PN"K23"2;
"VSS_AM37"
$PN"AM37"2;
"VSS_CB44"
$PN"CB44"2;
"VSS_CK31"
$PN"CK31"2;
"VSS_CY57"
$PN"CY57"2;
"VSS_DJ73"
$PN"DJ73"2;
"VSS_DJ68"
$PN"DJ68"2;
"VSS_DJ66"
$PN"DJ66"2;
"VSS_DJ63"
$PN"DJ63"2;
"VSS_DJ61"
$PN"DJ61"2;
"VSS_DJ59"
$PN"DJ59"2;
"VSS_DJ49"
$PN"DJ49"2;
"VSS_DJ43"
$PN"DJ43"2;
"VSS_DJ19"
$PN"DJ19"2;
"VSS_DJ15"
$PN"DJ15"2;
"VSS_DJ7"
$PN"DJ7"2;
"VSS_DH70"
$PN"DH70"2;
"VSS_DH68"
$PN"DH68"2;
"VSS_DH59"
$PN"DH59"2;
"VSS_DH55"
$PN"DH55"2;
"VSS_DH52"
$PN"DH52"2;
"VSS_DH49"
$PN"DH49"2;
"VSS_DH46"
$PN"DH46"2;
"VSS_DH43"
$PN"DH43"2;
"VSS_DH39"
$PN"DH39"2;
"VSS_DG75"
$PN"DG75"2;
"VSS_DG74"
$PN"DG74"2;
"VSS_DG70"
$PN"DG70"2;
"VSS_DG69"
$PN"DG69"2;
"VSS_DG68"
$PN"DG68"2;
"VSS_DG67"
$PN"DG67"2;
"VSS_DG66"
$PN"DG66"2;
"VSS_DG60"
$PN"DG60"2;
"VSS_DG59"
$PN"DG59"2;
"VSS_DG56"
$PN"DG56"2;
"VSS_DG55"
$PN"DG55"2;
"VSS_DG52"
$PN"DG52"2;
"VSS_DG49"
$PN"DG49"2;
"VSS_DG46"
$PN"DG46"2;
"VSS_DG27"
$PN"DG27"2;
"VSS_DG24"
$PN"DG24"2;
"VSS_DG21"
$PN"DG21"2;
"VSS_DG20"
$PN"DG20"2;
"VSS_DG18"
$PN"DG18"2;
"VSS_DG16"
$PN"DG16"2;
"VSS_DG15"
$PN"DG15"2;
"VSS_DG7"
$PN"DG7"2;
"VSS_DG6"
$PN"DG6"2;
"VSS_DG2"
$PN"DG2"2;
"VSS_DG1"
$PN"DG1"2;
"VSS_DF73"
$PN"DF73"2;
"VSS_DF72"
$PN"DF72"2;
"VSS_DF71"
$PN"DF71"2;
"VSS_DF65"
$PN"DF65"2;
"VSS_DF64"
$PN"DF64"2;
"VSS_DF63"
$PN"DF63"2;
"VSS_DF61"
$PN"DF61"2;
"VSS_DF59"
$PN"DF59"2;
"VSS_DF58"
$PN"DF58"2;
"VSS_DF57"
$PN"DF57"2;
"VSS_DF56"
$PN"DF56"2;
"VSS_DF52"
$PN"DF52"2;
"VSS_DF51"
$PN"DF51"2;
"VSS_DF50"
$PN"DF50"2;
"VSS_DF49"
$PN"DF49"2;
"VSS_DF48"
$PN"DF48"2;
"VSS_DF47"
$PN"DF47"2;
"VSS_DF46"
$PN"DF46"2;
"VSS_DF45"
$PN"DF45"2;
"VSS_DF44"
$PN"DF44"2;
"VSS_DF42"
$PN"DF42"2;
"VSS_DF39"
$PN"DF39"2;
"VSS_DF37"
$PN"DF37"2;
"VSS_DF35"
$PN"DF35"2;
"VSS_DF32"
$PN"DF32"2;
"VSS_DF29"
$PN"DF29"2;
"VSS_DF26"
$PN"DF26"2;
"VSS_DF23"
$PN"DF23"2;
"VSS_DF22"
$PN"DF22"2;
"VSS_DF20"
$PN"DF20"2;
"VSS_DF13"
$PN"DF13"1;
"VSS_DF12"
$PN"DF12"1;
"VSS_DF11"
$PN"DF11"1;
"VSS_DF10"
$PN"DF10"1;
"VSS_DF8"
$PN"DF8"1;
"VSS_DF6"
$PN"DF6"1;
"VSS_DF5"
$PN"DF5"1;
"VSS_DE68"
$PN"DE68"1;
"VSS_DE63"
$PN"DE63"1;
"VSS_DE61"
$PN"DE61"1;
"VSS_DE56"
$PN"DE56"1;
"VSS_DE33"
$PN"DE33"1;
"VSS_DE29"
$PN"DE29"1;
"VSS_DE26"
$PN"DE26"1;
"VSS_DE8"
$PN"DE8"1;
"VSS_DE6"
$PN"DE6"1;
"VSS_DE1"
$PN"DE1"1;
"VSS_DD73"
$PN"DD73"1;
"VSS_DD71"
$PN"DD71"1;
"VSS_DD68"
$PN"DD68"1;
"VSS_DD66"
$PN"DD66"1;
"VSS_DD53"
$PN"DD53"1;
"VSS_DD52"
$PN"DD52"1;
"VSS_DD50"
$PN"DD50"1;
"VSS_DD49"
$PN"DD49"1;
"VSS_DD47"
$PN"DD47"1;
"VSS_DD46"
$PN"DD46"1;
"VSS_DD44"
$PN"DD44"1;
"VSS_DD37"
$PN"DD37"1;
"VSS_DD36"
$PN"DD36"1;
"VSS_DD35"
$PN"DD35"1;
"VSS_DD33"
$PN"DD33"1;
"VSS_DD32"
$PN"DD32"1;
"VSS_DD30"
$PN"DD30"1;
"VSS_DD29"
$PN"DD29"1;
"VSS_DD19"
$PN"DD19"1;
"VSS_DD17"
$PN"DD17"1;
"VSS_DD15"
$PN"DD15"1;
"VSS_DD12"
$PN"DD12"1;
"VSS_DD10"
$PN"DD10"1;
"VSS_DD8"
$PN"DD8"1;
"VSS_DD5"
$PN"DD5"1;
"VSS_DC68"
$PN"DC68"1;
"VSS_DC65"
$PN"DC65"1;
"VSS_DC63"
$PN"DC63"1;
"VSS_DC61"
$PN"DC61"1;
"VSS_DC58"
$PN"DC58"1;
"VSS_DC56"
$PN"DC56"1;
"VSS_DC54"
$PN"DC54"1;
"VSS_DC42"
$PN"DC42"1;
"VSS_DC34"
$PN"DC34"1;
"VSS_DC31"
$PN"DC31"1;
"VSS_DC28"
$PN"DC28"1;
"VSS_DC25"
$PN"DC25"1;
"VSS_DC22"
$PN"DC22"1;
"VSS_DC20"
$PN"DC20"1;
"VSS_DC18"
$PN"DC18"1;
"VSS_DC11"
$PN"DC11"1;
"VSS_DC8"
$PN"DC8"1;
"VSS_DC6"
$PN"DC6"1;
"VSS_DC4"
$PN"DC4"1;
"VSS_DC1"
$PN"DC1"1;
"VSS_DB73"
$PN"DB73"1;
"VSS_DB68"
$PN"DB68"1;
"VSS_DB66"
$PN"DB66"1;
"VSS_DB61"
$PN"DB61"1;
"VSS_DB45"
$PN"DB45"1;
"VSS_DB42"
$PN"DB42"1;
"VSS_DB39"
$PN"DB39"1;
"VSS_DB37"
$PN"DB37"1;
"VSS_DB34"
$PN"DB34"1;
"VSS_DB31"
$PN"DB31"1;
"VSS_DB28"
$PN"DB28"1;
"VSS_DB10"
$PN"DB10"1;
"VSS_DB8"
$PN"DB8"1;
"VSS_DB3"
$PN"DB3"1;
"VSS_DA75"
$PN"DA75"1;
"VSS_DA72"
$PN"DA72"1;
"VSS_DH66"
$PN"DH66"2;
"VSS_DH64"
$PN"DH64"2;
"VSS_DH63"
$PN"DH63"2;
"VSS_DH61"
$PN"DH61"2;
"VSS_DH37"
$PN"DH37"2;
"VSS_DH18"
$PN"DH18"2;
"VSS_DH11"
$PN"DH11"2;
"VSS_DH5"
$PN"DH5"2;
"VSS_DG65"
$PN"DG65"2;
"VSS_DG63"
$PN"DG63"2;
"VSS_DG62"
$PN"DG62"2;
"VSS_DG61"
$PN"DG61"2;
"VSS_DG43"
$PN"DG43"2;
"VSS_DG41"
$PN"DG41"2;
"VSS_DG33"
$PN"DG33"2;
"VSS_DG30"
$PN"DG30"2;
"VSS_DG14"
$PN"DG14"2;
"VSS_DG13"
$PN"DG13"2;
"VSS_DG9"
$PN"DG9"2;
"VSS_DG8"
$PN"DG8"2;
"VSS_DF70"
$PN"DF70"2;
"VSS_DF68"
$PN"DF68"2;
"VSS_DF66"
$PN"DF66"2;
"VSS_DF54"
$PN"DF54"2;
"VSS_DF53"
$PN"DF53"2;
"VSS_DF43"
$PN"DF43"2;
"VSS_DF19"
$PN"DF19"1;
"VSS_DF18"
$PN"DF18"1;
"VSS_DF17"
$PN"DF17"1;
"VSS_DF15"
$PN"DF15"1;
"VSS_DF4"
$PN"DF4"1;
"VSS_DF3"
$PN"DF3"1;
"VSS_DE75"
$PN"DE75"1;
"VSS_DE70"
$PN"DE70"1;
"VSS_DE23"
$PN"DE23"1;
"VSS_DE20"
$PN"DE20"1;
"VSS_DE15"
$PN"DE15"1;
"VSS_DE13"
$PN"DE13"1;
"VSS_DD64"
$PN"DD64"1;
"VSS_DD61"
$PN"DD61"1;
"VSS_DD59"
$PN"DD59"1;
"VSS_DD57"
$PN"DD57"1;
"VSS_DD43"
$PN"DD43"1;
"VSS_DD41"
$PN"DD41"1;
"VSS_DD40"
$PN"DD40"1;
"VSS_DD39"
$PN"DD39"1;
"VSS_DD27"
$PN"DD27"1;
"VSS_DD26"
$PN"DD26"1;
"VSS_DD24"
$PN"DD24"1;
"VSS_DD23"
$PN"DD23"1;
"VSS_DD3"
$PN"DD3"1;
"VSS_DC75"
$PN"DC75"1;
"VSS_DC72"
$PN"DC72"1;
"VSS_DC70"
$PN"DC70"1;
"VSS_DC51"
$PN"DC51"1;
"VSS_DC48"
$PN"DC48"1;
"VSS_DC45"
$PN"DC45"1;
"VSS_DC15"
$PN"DC15"1;
"VSS_DC13"
$PN"DC13"1;
"VSS_DB59"
$PN"DB59"1;
"VSS_DB54"
$PN"DB54"1;
"VSS_DB51"
$PN"DB51"1;
"VSS_DB48"
$PN"DB48"1;
"VSS_DB25"
$PN"DB25"1;
"VSS_DB22"
$PN"DB22"1;
"VSS_DB17"
$PN"DB17"1;
"VSS_DB15"
$PN"DB15"1;
END.
